(kicad_pcb
	(version 20260206)
	(generator "pcbnew")
	(generator_version "10.0")
	(general
		(thickness 1.6)
		(legacy_teardrops no)
	)
	(paper "A4")
	(title_block
		(title "Wiwynn_Tioga_Pass_MB.brd")
		(comment 1 "Tioga Pass / footprints 4608-4615 of 4770")
	)
	(layers
		(0 "F.Cu" signal "TOP")
		(4 "In1.Cu" signal "L2GND")
		(6 "In2.Cu" signal "L3")
		(8 "In3.Cu" signal "L4GND")
		(10 "In4.Cu" signal "L5")
		(12 "In5.Cu" signal "L6GND")
		(14 "In6.Cu" signal "L7VCC")
		(16 "In7.Cu" signal "L8VCC")
		(18 "In8.Cu" signal "L9GND")
		(20 "In9.Cu" signal "L10")
		(22 "In10.Cu" signal "L11GND")
		(24 "In11.Cu" signal "L12")
		(26 "In12.Cu" signal "L13GND")
		(2 "B.Cu" signal "BOTTOM")
		(9 "F.Adhes" user "F.Adhesive")
		(11 "B.Adhes" user "B.Adhesive")
		(13 "F.Paste" user "Package Geometry/Pastemask Top")
		(15 "B.Paste" user "Package Geometry/Pastemask Bottom")
		(5 "F.SilkS" user "Ref Des/Silkscreen Top")
		(7 "B.SilkS" user "Ref Des/Silkscreen Bottom")
		(1 "F.Mask" user "Board Geometry/Soldermask Top")
		(3 "B.Mask" user "Board Geometry/Soldermask Bottom")
		(17 "Dwgs.User" user "User.Drawings")
		(19 "Cmts.User" user "User.Comments")
		(21 "Eco1.User" user "User.Eco1")
		(23 "Eco2.User" user "User.Eco2")
		(25 "Edge.Cuts" user "Board Geometry/Outline")
		(27 "Margin" user)
		(31 "F.CrtYd" user "Package Geometry/Place Bound Top")
		(29 "B.CrtYd" user "Package Geometry/Place Bound Bottom")
		(35 "F.Fab" user "Ref Des/Assembly Top")
		(33 "B.Fab" user "Ref Des/Assembly Bottom")
	)
	(footprint ""
		(layer "B.Cu")
		(at 333.659226 -38.259766 90)
		(property "Reference" "C3T2"
			(at 0 0 90)
			(layer "B.SilkS")
			(hide yes)
			(effects
				(font
					(size 1.27 1.27)
				)
				(justify mirror)
			)
		)
		(property "Value" ""
			(at 0 0 90)
			(layer "B.Fab")
			(effects
				(font
					(size 1.27 1.27)
				)
				(justify mirror)
			)
		)
		(duplicate_pad_numbers_are_jumpers no)
		(fp_rect
			(start 0.500126 1.598422)
			(end -0.500126 -0.201422)
			(stroke
				(width 0)
				(type default)
			)
			(fill no)
			(layer "B.CrtYd")
		)
		(fp_line
			(start 0.500126 -0.201422)
			(end -0.500126 -0.201422)
			(stroke
				(width 0.1)
				(type default)
			)
			(layer "B.Fab")
		)
		(fp_line
			(start -0.500126 -0.201422)
			(end -0.500126 1.598422)
			(stroke
				(width 0.1)
				(type default)
			)
			(layer "B.Fab")
		)
		(fp_line
			(start 0.500126 1.598422)
			(end 0.500126 -0.201422)
			(stroke
				(width 0.1)
				(type default)
			)
			(layer "B.Fab")
		)
		(fp_line
			(start -0.500126 1.598422)
			(end 0.500126 1.598422)
			(stroke
				(width 0.1)
				(type default)
			)
			(layer "B.Fab")
		)
		(pad "1" smd rect
			(at 0 0)
			(size 0.889 0.9906)
			(layers "B.Cu" "B.Mask" "B.Paste")
			(net "P1V8_MCP_CPU0")
		)
		(pad "2" smd rect
			(at 0 1.397)
			(size 0.889 0.9906)
			(layers "B.Cu" "B.Mask" "B.Paste")
			(net "GND")
		)
		(zone
			(layer "B.Cu")
			(hatch none 0.5)
			(connect_pads
				(clearance 0)
			)
			(min_thickness 0.25)
			(keepout
				(tracks allowed)
				(vias not_allowed)
				(pads allowed)
				(copperpour not_allowed)
				(footprints allowed)
			)
			(placement
				(enabled no)
				(sheetname "")
			)
			(fill
				(thermal_gap 0.5)
				(thermal_bridge_width 0.5)
				(island_removal_mode 0)
			)
			(polygon
				(pts
					(xy 334.611726 -38.755066) (xy 334.103726 -38.755066) (xy 334.103726 -37.764466) (xy 334.611726 -37.764466)
				)
			)
		)
		(zone
			(layer "B.Cu")
			(hatch none 0.5)
			(connect_pads
				(clearance 0)
			)
			(min_thickness 0.25)
			(keepout
				(tracks not_allowed)
				(vias allowed)
				(pads allowed)
				(copperpour not_allowed)
				(footprints allowed)
			)
			(placement
				(enabled no)
				(sheetname "")
			)
			(fill
				(thermal_gap 0.5)
				(thermal_bridge_width 0.5)
				(island_removal_mode 0)
			)
			(polygon
				(pts
					(xy 334.611726 -38.755066) (xy 334.103726 -38.755066) (xy 334.103726 -37.764466) (xy 334.611726 -37.764466)
				)
			)
		)
	)
	(footprint ""
		(layer "B.Cu")
		(at 467.868 -4.3815)
		(property "Reference" "R7E22"
			(at 0 0 0)
			(layer "B.SilkS")
			(hide yes)
			(effects
				(font
					(size 1.27 1.27)
				)
				(justify mirror)
			)
		)
		(property "Value" ""
			(at 0 0 0)
			(layer "B.Fab")
			(effects
				(font
					(size 1.27 1.27)
				)
				(justify mirror)
			)
		)
		(duplicate_pad_numbers_are_jumpers no)
		(fp_poly
			(pts
				(xy 0.2794 -0.1016) (xy -0.2794 -0.1016) (xy -0.2794 0.9906) (xy 0.2794 0.9906)
			)
			(stroke
				(width 0)
				(type default)
			)
			(fill no)
			(layer "B.CrtYd")
		)
		(fp_line
			(start -0.2794 -0.1016)
			(end 0.2794 -0.1016)
			(stroke
				(width 0.1)
				(type default)
			)
			(layer "B.Fab")
		)
		(fp_line
			(start -0.2794 0.9906)
			(end -0.2794 -0.1016)
			(stroke
				(width 0.1)
				(type default)
			)
			(layer "B.Fab")
		)
		(fp_line
			(start 0.2794 -0.1016)
			(end 0.2794 0.9906)
			(stroke
				(width 0.1)
				(type default)
			)
			(layer "B.Fab")
		)
		(fp_line
			(start 0.2794 0.9906)
			(end -0.2794 0.9906)
			(stroke
				(width 0.1)
				(type default)
			)
			(layer "B.Fab")
		)
		(pad "1" smd rect
			(at 0 0 180)
			(size 0.508 0.508)
			(layers "B.Cu" "B.Mask" "B.Paste")
			(net "FM_PWRBRK_N")
		)
		(pad "2" smd rect
			(at 0 0.889 180)
			(size 0.508 0.508)
			(layers "B.Cu" "B.Mask" "B.Paste")
			(net "FM_PWRBRK_SLOT_N")
		)
		(zone
			(layer "B.Cu")
			(hatch none 0.5)
			(connect_pads
				(clearance 0)
			)
			(min_thickness 0.25)
			(keepout
				(tracks allowed)
				(vias not_allowed)
				(pads allowed)
				(copperpour not_allowed)
				(footprints allowed)
			)
			(placement
				(enabled no)
				(sheetname "")
			)
			(fill
				(thermal_gap 0.5)
				(thermal_bridge_width 0.5)
				(island_removal_mode 0)
			)
			(polygon
				(pts
					(xy 468.122 -4.1275) (xy 467.614 -4.1275) (xy 467.614 -3.7465) (xy 468.122 -3.7465)
				)
			)
		)
		(zone
			(layer "B.Cu")
			(hatch none 0.5)
			(connect_pads
				(clearance 0)
			)
			(min_thickness 0.25)
			(keepout
				(tracks not_allowed)
				(vias allowed)
				(pads allowed)
				(copperpour not_allowed)
				(footprints allowed)
			)
			(placement
				(enabled no)
				(sheetname "")
			)
			(fill
				(thermal_gap 0.5)
				(thermal_bridge_width 0.5)
				(island_removal_mode 0)
			)
			(polygon
				(pts
					(xy 468.122 -3.7465) (xy 467.614 -3.7465) (xy 467.614 -4.1275) (xy 468.122 -4.1275)
				)
			)
		)
	)
	(footprint ""
		(layer "B.Cu")
		(at 417.576 -6.5405)
		(property "Reference" "R3P50"
			(at 0 0 0)
			(layer "B.SilkS")
			(hide yes)
			(effects
				(font
					(size 1.27 1.27)
				)
				(justify mirror)
			)
		)
		(property "Value" ""
			(at 0 0 0)
			(layer "B.Fab")
			(effects
				(font
					(size 1.27 1.27)
				)
				(justify mirror)
			)
		)
		(duplicate_pad_numbers_are_jumpers no)
		(fp_rect
			(start -0.2794 0.9906)
			(end 0.2794 -0.1016)
			(stroke
				(width 0)
				(type default)
			)
			(fill no)
			(layer "B.CrtYd")
		)
		(fp_line
			(start -0.2794 -0.1016)
			(end 0.2794 -0.1016)
			(stroke
				(width 0.1)
				(type default)
			)
			(layer "B.Fab")
		)
		(fp_line
			(start -0.2794 0.9906)
			(end -0.2794 -0.1016)
			(stroke
				(width 0.1)
				(type default)
			)
			(layer "B.Fab")
		)
		(fp_line
			(start 0.2794 -0.1016)
			(end 0.2794 0.9906)
			(stroke
				(width 0.1)
				(type default)
			)
			(layer "B.Fab")
		)
		(fp_line
			(start 0.2794 0.9906)
			(end -0.2794 0.9906)
			(stroke
				(width 0.1)
				(type default)
			)
			(layer "B.Fab")
		)
		(pad "1" smd rect
			(at 0 0 180)
			(size 0.508 0.508)
			(layers "B.Cu" "B.Mask" "B.Paste")
			(net "P3V3_STBY")
		)
		(pad "2" smd rect
			(at 0 0.889 180)
			(size 0.508 0.508)
			(layers "B.Cu" "B.Mask" "B.Paste")
			(net "PWRGD_P3V3_STBY")
		)
		(zone
			(layer "B.Cu")
			(hatch none 0.5)
			(connect_pads
				(clearance 0)
			)
			(min_thickness 0.25)
			(keepout
				(tracks allowed)
				(vias not_allowed)
				(pads allowed)
				(copperpour not_allowed)
				(footprints allowed)
			)
			(placement
				(enabled no)
				(sheetname "")
			)
			(fill
				(thermal_gap 0.5)
				(thermal_bridge_width 0.5)
				(island_removal_mode 0)
			)
			(polygon
				(pts
					(xy 417.322 -5.9055) (xy 417.83 -5.9055) (xy 417.83 -6.2865) (xy 417.322 -6.2865)
				)
			)
		)
		(zone
			(layer "B.Cu")
			(hatch none 0.5)
			(connect_pads
				(clearance 0)
			)
			(min_thickness 0.25)
			(keepout
				(tracks not_allowed)
				(vias allowed)
				(pads allowed)
				(copperpour not_allowed)
				(footprints allowed)
			)
			(placement
				(enabled no)
				(sheetname "")
			)
			(fill
				(thermal_gap 0.5)
				(thermal_bridge_width 0.5)
				(island_removal_mode 0)
			)
			(polygon
				(pts
					(xy 417.322 -5.9055) (xy 417.83 -5.9055) (xy 417.83 -6.2865) (xy 417.322 -6.2865)
				)
			)
		)
	)
	(footprint ""
		(layer "B.Cu")
		(at 49.4284 -78.359)
		(property "Reference" "C9P10"
			(at 0 0 0)
			(layer "B.SilkS")
			(hide yes)
			(effects
				(font
					(size 1.27 1.27)
				)
				(justify mirror)
			)
		)
		(property "Value" ""
			(at 0 0 0)
			(layer "B.Fab")
			(effects
				(font
					(size 1.27 1.27)
				)
				(justify mirror)
			)
		)
		(duplicate_pad_numbers_are_jumpers no)
		(fp_poly
			(pts
				(xy 0.4953 -0.2032) (xy -0.4953 -0.2032) (xy -0.4953 1.6002) (xy 0.4953 1.6002)
			)
			(stroke
				(width 0)
				(type default)
			)
			(fill no)
			(layer "B.CrtYd")
		)
		(fp_line
			(start -0.4953 -0.2032)
			(end -0.4953 1.6002)
			(stroke
				(width 0.1)
				(type default)
			)
			(layer "B.Fab")
		)
		(fp_line
			(start -0.4953 1.6002)
			(end 0.4953 1.6002)
			(stroke
				(width 0.1)
				(type default)
			)
			(layer "B.Fab")
		)
		(fp_line
			(start 0.4953 -0.2032)
			(end -0.4953 -0.2032)
			(stroke
				(width 0.1)
				(type default)
			)
			(layer "B.Fab")
		)
		(fp_line
			(start 0.4953 1.6002)
			(end 0.4953 -0.2032)
			(stroke
				(width 0.1)
				(type default)
			)
			(layer "B.Fab")
		)
		(pad "1" smd rect
			(at 0 0 180)
			(size 0.762 0.889)
			(layers "B.Cu" "B.Mask" "B.Paste")
			(net "PVCCIN_CPU1")
		)
		(pad "2" smd rect
			(at 0 1.397 180)
			(size 0.762 0.889)
			(layers "B.Cu" "B.Mask" "B.Paste")
			(net "GND")
		)
		(zone
			(layer "B.Cu")
			(hatch none 0.5)
			(connect_pads
				(clearance 0)
			)
			(min_thickness 0.25)
			(keepout
				(tracks not_allowed)
				(vias allowed)
				(pads allowed)
				(copperpour not_allowed)
				(footprints allowed)
			)
			(placement
				(enabled no)
				(sheetname "")
			)
			(fill
				(thermal_gap 0.5)
				(thermal_bridge_width 0.5)
				(island_removal_mode 0)
			)
			(polygon
				(pts
					(xy 49.8094 -77.9145) (xy 49.0474 -77.9145) (xy 49.0474 -77.4065) (xy 49.8094 -77.4065)
				)
			)
		)
	)
	(footprint ""
		(layer "B.Cu")
		(at 19.05 -95.5294)
		(property "Reference" "R9N8"
			(at 0 0 0)
			(layer "B.SilkS")
			(hide yes)
			(effects
				(font
					(size 1.27 1.27)
				)
				(justify mirror)
			)
		)
		(property "Value" ""
			(at 0 0 0)
			(layer "B.Fab")
			(effects
				(font
					(size 1.27 1.27)
				)
				(justify mirror)
			)
		)
		(duplicate_pad_numbers_are_jumpers no)
		(fp_poly
			(pts
				(xy 0.2794 -0.1016) (xy -0.2794 -0.1016) (xy -0.2794 0.9906) (xy 0.2794 0.9906)
			)
			(stroke
				(width 0)
				(type default)
			)
			(fill no)
			(layer "B.CrtYd")
		)
		(fp_line
			(start -0.2794 -0.1016)
			(end 0.2794 -0.1016)
			(stroke
				(width 0.1)
				(type default)
			)
			(layer "B.Fab")
		)
		(fp_line
			(start -0.2794 0.9906)
			(end -0.2794 -0.1016)
			(stroke
				(width 0.1)
				(type default)
			)
			(layer "B.Fab")
		)
		(fp_line
			(start 0.2794 -0.1016)
			(end 0.2794 0.9906)
			(stroke
				(width 0.1)
				(type default)
			)
			(layer "B.Fab")
		)
		(fp_line
			(start 0.2794 0.9906)
			(end -0.2794 0.9906)
			(stroke
				(width 0.1)
				(type default)
			)
			(layer "B.Fab")
		)
		(pad "1" smd rect
			(at 0 0 180)
			(size 0.508 0.508)
			(layers "B.Cu" "B.Mask" "B.Paste")
			(net "VR_PVCCIN_CPU1_XADDR1")
		)
		(pad "2" smd rect
			(at 0 0.889 180)
			(size 0.508 0.508)
			(layers "B.Cu" "B.Mask" "B.Paste")
			(net "GND")
		)
		(zone
			(layer "B.Cu")
			(hatch none 0.5)
			(connect_pads
				(clearance 0)
			)
			(min_thickness 0.25)
			(keepout
				(tracks allowed)
				(vias not_allowed)
				(pads allowed)
				(copperpour not_allowed)
				(footprints allowed)
			)
			(placement
				(enabled no)
				(sheetname "")
			)
			(fill
				(thermal_gap 0.5)
				(thermal_bridge_width 0.5)
				(island_removal_mode 0)
			)
			(polygon
				(pts
					(xy 19.304 -95.2754) (xy 18.796 -95.2754) (xy 18.796 -94.8944) (xy 19.304 -94.8944)
				)
			)
		)
		(zone
			(layer "B.Cu")
			(hatch none 0.5)
			(connect_pads
				(clearance 0)
			)
			(min_thickness 0.25)
			(keepout
				(tracks not_allowed)
				(vias allowed)
				(pads allowed)
				(copperpour not_allowed)
				(footprints allowed)
			)
			(placement
				(enabled no)
				(sheetname "")
			)
			(fill
				(thermal_gap 0.5)
				(thermal_bridge_width 0.5)
				(island_removal_mode 0)
			)
			(polygon
				(pts
					(xy 19.304 -94.8944) (xy 18.796 -94.8944) (xy 18.796 -95.2754) (xy 19.304 -95.2754)
				)
			)
		)
	)
	(footprint ""
		(layer "B.Cu")
		(at 399.530824 -125.627384 90)
		(property "Reference" "C2M3"
			(at 0 0 90)
			(layer "B.SilkS")
			(hide yes)
			(effects
				(font
					(size 1.27 1.27)
				)
				(justify mirror)
			)
		)
		(property "Value" ""
			(at 0 0 90)
			(layer "B.Fab")
			(effects
				(font
					(size 1.27 1.27)
				)
				(justify mirror)
			)
		)
		(duplicate_pad_numbers_are_jumpers no)
		(fp_poly
			(pts
				(xy -0.3048 -0.1016) (xy -0.3048 0.9906) (xy 0.3048 0.9906) (xy 0.3048 -0.1016)
			)
			(stroke
				(width 0)
				(type default)
			)
			(fill no)
			(layer "B.CrtYd")
		)
		(fp_line
			(start 0.3048 -0.1016)
			(end 0.3048 0.9906)
			(stroke
				(width 0.1)
				(type default)
			)
			(layer "B.Fab")
		)
		(fp_line
			(start -0.3048 -0.1016)
			(end 0.3048 -0.1016)
			(stroke
				(width 0.1)
				(type default)
			)
			(layer "B.Fab")
		)
		(fp_line
			(start 0.3048 0.9906)
			(end -0.3048 0.9906)
			(stroke
				(width 0.1)
				(type default)
			)
			(layer "B.Fab")
		)
		(fp_line
			(start -0.3048 0.9906)
			(end -0.3048 -0.1016)
			(stroke
				(width 0.1)
				(type default)
			)
			(layer "B.Fab")
		)
		(pad "1" smd rect
			(at 0 0 270)
			(size 0.508 0.508)
			(layers "B.Cu" "B.Mask" "B.Paste")
			(net "P2E_SSB_BMC_TX_DN")
		)
		(pad "2" smd rect
			(at 0 0.889 270)
			(size 0.508 0.508)
			(layers "B.Cu" "B.Mask" "B.Paste")
			(net "P2E_SSB_BMC_TX_C_DN")
		)
		(zone
			(layer "B.Cu")
			(hatch none 0.5)
			(connect_pads
				(clearance 0)
			)
			(min_thickness 0.25)
			(keepout
				(tracks allowed)
				(vias not_allowed)
				(pads allowed)
				(copperpour not_allowed)
				(footprints allowed)
			)
			(placement
				(enabled no)
				(sheetname "")
			)
			(fill
				(thermal_gap 0.5)
				(thermal_bridge_width 0.5)
				(island_removal_mode 0)
			)
			(polygon
				(pts
					(xy 399.784824 -125.881384) (xy 399.784824 -125.373384) (xy 400.165824 -125.373384) (xy 400.165824 -125.881384)
				)
			)
		)
		(zone
			(layer "B.Cu")
			(hatch none 0.5)
			(connect_pads
				(clearance 0)
			)
			(min_thickness 0.25)
			(keepout
				(tracks not_allowed)
				(vias allowed)
				(pads allowed)
				(copperpour not_allowed)
				(footprints allowed)
			)
			(placement
				(enabled no)
				(sheetname "")
			)
			(fill
				(thermal_gap 0.5)
				(thermal_bridge_width 0.5)
				(island_removal_mode 0)
			)
			(polygon
				(pts
					(xy 400.165824 -125.881384) (xy 400.165824 -125.373384) (xy 399.784824 -125.373384) (xy 399.784824 -125.881384)
				)
			)
		)
	)
	(footprint ""
		(layer "B.Cu")
		(at 322.9737 -27.411172 90)
		(property "Reference" "R4T9"
			(at 0 0 90)
			(layer "B.SilkS")
			(hide yes)
			(effects
				(font
					(size 1.27 1.27)
				)
				(justify mirror)
			)
		)
		(property "Value" ""
			(at 0 0 90)
			(layer "B.Fab")
			(effects
				(font
					(size 1.27 1.27)
				)
				(justify mirror)
			)
		)
		(duplicate_pad_numbers_are_jumpers no)
		(fp_poly
			(pts
				(xy 0.2794 -0.1016) (xy -0.2794 -0.1016) (xy -0.2794 0.9906) (xy 0.2794 0.9906)
			)
			(stroke
				(width 0)
				(type default)
			)
			(fill no)
			(layer "B.CrtYd")
		)
		(fp_line
			(start 0.2794 -0.1016)
			(end 0.2794 0.9906)
			(stroke
				(width 0.1)
				(type default)
			)
			(layer "B.Fab")
		)
		(fp_line
			(start -0.2794 -0.1016)
			(end 0.2794 -0.1016)
			(stroke
				(width 0.1)
				(type default)
			)
			(layer "B.Fab")
		)
		(fp_line
			(start 0.2794 0.9906)
			(end -0.2794 0.9906)
			(stroke
				(width 0.1)
				(type default)
			)
			(layer "B.Fab")
		)
		(fp_line
			(start -0.2794 0.9906)
			(end -0.2794 -0.1016)
			(stroke
				(width 0.1)
				(type default)
			)
			(layer "B.Fab")
		)
		(pad "1" smd rect
			(at 0 0 270)
			(size 0.508 0.508)
			(layers "B.Cu" "B.Mask" "B.Paste")
			(net "SMB_DDR_ABC_VPP_SCL_R")
		)
		(pad "2" smd rect
			(at 0 0.889 270)
			(size 0.508 0.508)
			(layers "B.Cu" "B.Mask" "B.Paste")
			(net "SMB_DDR_ABC_VPP_SCL")
		)
		(zone
			(layer "B.Cu")
			(hatch none 0.5)
			(connect_pads
				(clearance 0)
			)
			(min_thickness 0.25)
			(keepout
				(tracks allowed)
				(vias not_allowed)
				(pads allowed)
				(copperpour not_allowed)
				(footprints allowed)
			)
			(placement
				(enabled no)
				(sheetname "")
			)
			(fill
				(thermal_gap 0.5)
				(thermal_bridge_width 0.5)
				(island_removal_mode 0)
			)
			(polygon
				(pts
					(xy 323.2277 -27.665172) (xy 323.2277 -27.157172) (xy 323.6087 -27.157172) (xy 323.6087 -27.665172)
				)
			)
		)
		(zone
			(layer "B.Cu")
			(hatch none 0.5)
			(connect_pads
				(clearance 0)
			)
			(min_thickness 0.25)
			(keepout
				(tracks not_allowed)
				(vias allowed)
				(pads allowed)
				(copperpour not_allowed)
				(footprints allowed)
			)
			(placement
				(enabled no)
				(sheetname "")
			)
			(fill
				(thermal_gap 0.5)
				(thermal_bridge_width 0.5)
				(island_removal_mode 0)
			)
			(polygon
				(pts
					(xy 323.6087 -27.665172) (xy 323.6087 -27.157172) (xy 323.2277 -27.157172) (xy 323.2277 -27.665172)
				)
			)
		)
	)
	(footprint ""
		(layer "B.Cu")
		(at 99.427792 -69.098414 -90)
		(property "Reference" "C8P30"
			(at 0 0 90)
			(layer "B.SilkS")
			(hide yes)
			(effects
				(font
					(size 1.27 1.27)
				)
				(justify mirror)
			)
		)
		(property "Value" ""
			(at 0 0 90)
			(layer "B.Fab")
			(effects
				(font
					(size 1.27 1.27)
				)
				(justify mirror)
			)
		)
		(duplicate_pad_numbers_are_jumpers no)
		(fp_poly
			(pts
				(xy 0.7239 -0.2159) (xy -0.7239 -0.2159) (xy -0.7239 1.9939) (xy 0.7239 1.9939)
			)
			(stroke
				(width 0)
				(type default)
			)
			(fill no)
			(layer "B.CrtYd")
		)
		(fp_line
			(start -0.7239 1.9939)
			(end -0.7239 -0.2159)
			(stroke
				(width 0.1)
				(type default)
			)
			(layer "B.Fab")
		)
		(fp_line
			(start 0.7239 1.9939)
			(end -0.7239 1.9939)
			(stroke
				(width 0.1)
				(type default)
			)
			(layer "B.Fab")
		)
		(fp_line
			(start -0.7239 -0.2159)
			(end 0.7239 -0.2159)
			(stroke
				(width 0.1)
				(type default)
			)
			(layer "B.Fab")
		)
		(fp_line
			(start 0.7239 -0.2159)
			(end 0.7239 1.9939)
			(stroke
				(width 0.1)
				(type default)
			)
			(layer "B.Fab")
		)
		(pad "1" smd rect
			(at 0 0 90)
			(size 1.27 1.016)
			(layers "B.Cu" "B.Mask" "B.Paste")
			(net "PVDDQ_GHJ")
		)
		(pad "2" smd rect
			(at 0 1.778 90)
			(size 1.27 1.016)
			(layers "B.Cu" "B.Mask" "B.Paste")
			(net "GND")
		)
		(zone
			(layer "B.Cu")
			(hatch none 0.5)
			(connect_pads
				(clearance 0)
			)
			(min_thickness 0.25)
			(keepout
				(tracks not_allowed)
				(vias allowed)
				(pads allowed)
				(copperpour not_allowed)
				(footprints allowed)
			)
			(placement
				(enabled no)
				(sheetname "")
			)
			(fill
				(thermal_gap 0.5)
				(thermal_bridge_width 0.5)
				(island_removal_mode 0)
			)
			(polygon
				(pts
					(xy 98.919792 -68.463414) (xy 98.919792 -69.733414) (xy 98.157792 -69.733414) (xy 98.157792 -68.463414)
				)
			)
		)
	)
)
